# T6G (Grand Teton) — schematic netlist excerpt (pin names and nets, part order shuffled) for the footprints in the layout excerpt that follows; sources: Cadence DE-HDL packaged netlist, KiCad conversion of 04192023_DAF0TMB3IC0_F0TG_MB_C_brd_V02_OCP.brd

C6657  Q_CAP_DIFFBUS  DIFF BUS_0.22UF 6.3V 20% X6S  pkg C0201  page 319 : \1\ = P5E_CPU1_P0_TX_BUF_C_DP<14> ; \2\ = P5E_CPU1_P0_TX_BUF_DP<14>
R6149  Q_RES  1K 1% EMPTY  pkg 0402LF  page 84 : A = FAB_BMC_REV_ID2 ; B = GND

PL63  Q_INDUCTOR4P_14  150NH IND  pkg L_TLM117513Q-151QL_11X7-5XA  page 198
  \1\  = SW_PVDDCR_SOC_P0_SW1
  \2\  = IND_SOC_P0_CPL2
  \3\  = GND
  \4\  = PVDDCR_SOC_P0

(kicad_pcb
	(version 20260206)
	(generator "pcbnew")
	(generator_version "10.0")
	(general
		(thickness 1.6)
		(legacy_teardrops no)
	)
	(paper "A4")
	(title_block
		(title "04192023_DAF0TMB3IC0_F0TG_MB_C_brd_V02_OCP.brd")
		(comment 1 "Grand Teton / footprints 1948-1950 of 8354")
	)
	(layers
		(0 "F.Cu" signal "TOP")
		(4 "In1.Cu" signal "GND")
		(6 "In2.Cu" signal "IN1")
		(8 "In3.Cu" signal "GND1")
		(10 "In4.Cu" signal "IN2")
		(12 "In5.Cu" signal "GND2")
		(14 "In6.Cu" signal "IN3")
		(16 "In7.Cu" signal "GND3")
		(18 "In8.Cu" signal "VCC")
		(20 "In9.Cu" signal "VCC1")
		(22 "In10.Cu" signal "GND4")
		(24 "In11.Cu" signal "IN4")
		(26 "In12.Cu" signal "GND5")
		(28 "In13.Cu" signal "IN5")
		(30 "In14.Cu" signal "GND6")
		(32 "In15.Cu" signal "IN6")
		(34 "In16.Cu" signal "GND7")
		(2 "B.Cu" signal "BOTTOM")
		(9 "F.Adhes" user "F.Adhesive")
		(11 "B.Adhes" user "B.Adhesive")
		(13 "F.Paste" user "Package Geometry/Pastemask Top")
		(15 "B.Paste" user "Package Geometry/Pastemask Bottom")
		(5 "F.SilkS" user "Ref Des/Silkscreen Top")
		(7 "B.SilkS" user "Ref Des/Silkscreen Bottom")
		(1 "F.Mask" user "Board Geometry/Soldermask Top")
		(3 "B.Mask" user "Board Geometry/Soldermask Bottom")
		(17 "Dwgs.User" user "User.Drawings")
		(19 "Cmts.User" user "User.Comments")
		(21 "Eco1.User" user "User.Eco1")
		(23 "Eco2.User" user "User.Eco2")
		(25 "Edge.Cuts" user "Board Geometry/Outline")
		(27 "Margin" user)
		(31 "F.CrtYd" user "Package Geometry/Place Bound Top")
		(29 "B.CrtYd" user "Package Geometry/Place Bound Bottom")
		(35 "F.Fab" user "Ref Des/Assembly Top")
		(33 "B.Fab" user "Ref Des/Assembly Bottom")
	)
	(footprint ""
		(layer "F.Cu")
		(at 180.710332 -92.67444 -90)
		(property "Reference" "R6149"
			(at 0 0 270)
			(layer "F.SilkS")
			(hide yes)
			(effects
				(font
					(size 1.27 1.27)
				)
			)
		)
		(property "Value" ""
			(at 0 0 270)
			(layer "F.Fab")
			(effects
				(font
					(size 1.27 1.27)
				)
			)
		)
		(duplicate_pad_numbers_are_jumpers no)
		(fp_line
			(start -0.7874 0.4064)
			(end -0.7874 -0.4064)
			(stroke
				(width 0.1524)
				(type default)
			)
			(layer "F.SilkS")
		)
		(fp_line
			(start 0.7874 0.4064)
			(end -0.7874 0.4064)
			(stroke
				(width 0.1524)
				(type default)
			)
			(layer "F.SilkS")
		)
		(fp_line
			(start -0.7874 -0.4064)
			(end 0.7874 -0.4064)
			(stroke
				(width 0.1524)
				(type default)
			)
			(layer "F.SilkS")
		)
		(fp_line
			(start 0.7874 -0.4064)
			(end 0.7874 0.4064)
			(stroke
				(width 0.1524)
				(type default)
			)
			(layer "F.SilkS")
		)
		(fp_line
			(start -0.67945 0.3048)
			(end -0.67945 -0.305054)
			(stroke
				(width 0.1)
				(type default)
			)
			(layer "F.Fab")
		)
		(fp_line
			(start -0.12065 0.3048)
			(end -0.67945 0.3048)
			(stroke
				(width 0.1)
				(type default)
			)
			(layer "F.Fab")
		)
		(fp_line
			(start 0.120396 0.3048)
			(end 0.120396 0.2794)
			(stroke
				(width 0.1)
				(type default)
			)
			(layer "F.Fab")
		)
		(fp_line
			(start 0.67945 0.3048)
			(end 0.120396 0.3048)
			(stroke
				(width 0.1)
				(type default)
			)
			(layer "F.Fab")
		)
		(fp_line
			(start -0.12065 0.2794)
			(end -0.12065 0.3048)
			(stroke
				(width 0.1)
				(type default)
			)
			(layer "F.Fab")
		)
		(fp_line
			(start 0.120396 0.2794)
			(end -0.12065 0.2794)
			(stroke
				(width 0.1)
				(type default)
			)
			(layer "F.Fab")
		)
		(fp_line
			(start -0.12065 -0.2794)
			(end 0.12065 -0.2794)
			(stroke
				(width 0.1)
				(type default)
			)
			(layer "F.Fab")
		)
		(fp_line
			(start 0.12065 -0.2794)
			(end 0.12065 -0.3048)
			(stroke
				(width 0.1)
				(type default)
			)
			(layer "F.Fab")
		)
		(fp_line
			(start 0.12065 -0.3048)
			(end 0.67945 -0.3048)
			(stroke
				(width 0.1)
				(type default)
			)
			(layer "F.Fab")
		)
		(fp_line
			(start 0.67945 -0.3048)
			(end 0.67945 0.3048)
			(stroke
				(width 0.1)
				(type default)
			)
			(layer "F.Fab")
		)
		(fp_line
			(start -0.67945 -0.305054)
			(end -0.12065 -0.305054)
			(stroke
				(width 0.1)
				(type default)
			)
			(layer "F.Fab")
		)
		(fp_line
			(start -0.12065 -0.305054)
			(end -0.12065 -0.2794)
			(stroke
				(width 0.1)
				(type default)
			)
			(layer "F.Fab")
		)
		(pad "1" smd circle
			(at -0.40005 0 270)
			(size 0 0)
			(layers "F.Cu" "F.Mask" "F.Paste")
			(net "FAB_BMC_REV_ID2")
		)
		(pad "2" smd circle
			(at 0.40005 0 270)
			(size 0 0)
			(layers "F.Cu" "F.Mask" "F.Paste")
			(net "GND")
		)
	)
	(footprint ""
		(layer "F.Cu")
		(at 398.046956 -186.488324 180)
		(property "Reference" "PL63"
			(at -4.603242 2.798064 90)
			(unlocked yes)
			(layer "F.SilkS")
			(effects
				(font
					(size 0.7874 0.5842)
					(thickness 0.1524)
				)
				(justify left)
			)
		)
		(property "Value" ""
			(at 0 0 180)
			(layer "F.Fab")
			(effects
				(font
					(size 1.27 1.27)
				)
			)
		)
		(duplicate_pad_numbers_are_jumpers no)
		(fp_line
			(start 3.750056 5.500116)
			(end 3.750056 -5.500116)
			(stroke
				(width 0.1524)
				(type default)
			)
			(layer "F.SilkS")
		)
		(fp_line
			(start 3.750056 -5.500116)
			(end 2.393442 -5.500116)
			(stroke
				(width 0.1524)
				(type default)
			)
			(layer "F.SilkS")
		)
		(fp_line
			(start 2.393442 5.500116)
			(end 3.750056 5.500116)
			(stroke
				(width 0.1524)
				(type default)
			)
			(layer "F.SilkS")
		)
		(fp_line
			(start -2.393442 5.500116)
			(end -3.750056 5.500116)
			(stroke
				(width 0.1524)
				(type default)
			)
			(layer "F.SilkS")
		)
		(fp_line
			(start -3.750056 5.500116)
			(end -3.750056 -5.500116)
			(stroke
				(width 0.1524)
				(type default)
			)
			(layer "F.SilkS")
		)
		(fp_line
			(start -3.750056 -5.500116)
			(end -2.393442 -5.500116)
			(stroke
				(width 0.1524)
				(type default)
			)
			(layer "F.SilkS")
		)
		(fp_poly
			(pts
				(xy -3.9116 -4.249928) (xy -4.543044 -3.934206) (xy -4.543044 -4.56565)
			)
			(stroke
				(width 0)
				(type default)
			)
			(fill yes)
			(layer "F.SilkS")
		)
		(fp_line
			(start 3.750056 5.500116)
			(end 3.750056 -5.500116)
			(stroke
				(width 0.1)
				(type default)
			)
			(layer "F.Fab")
		)
		(fp_line
			(start 3.750056 -5.500116)
			(end -3.750056 -5.500116)
			(stroke
				(width 0.1)
				(type default)
			)
			(layer "F.Fab")
		)
		(fp_line
			(start -3.750056 5.500116)
			(end 3.750056 5.500116)
			(stroke
				(width 0.1)
				(type default)
			)
			(layer "F.Fab")
		)
		(fp_line
			(start -3.750056 -5.500116)
			(end -3.750056 5.500116)
			(stroke
				(width 0.1)
				(type default)
			)
			(layer "F.Fab")
		)
		(fp_poly
			(pts
				(xy -4.9276 -4.757928) (xy -4.9276 -3.741928) (xy -3.9116 -4.249928)
			)
			(stroke
				(width 0)
				(type default)
			)
			(fill yes)
			(layer "F.Fab")
		)
		(pad "1" smd rect
			(at 0 -4.249928 90)
			(size 2.413 4.5212)
			(layers "F.Cu" "F.Mask" "F.Paste")
			(net "SW_PVDDCR_SOC_P0_SW1")
		)
		(pad "2" smd rect
			(at 0 -1.175004 90)
			(size 1.3716 4.5212)
			(layers "F.Cu" "F.Mask" "F.Paste")
			(net "IND_SOC_P0_CPL2")
		)
		(pad "3" smd rect
			(at 0 1.175004 90)
			(size 1.3716 4.5212)
			(layers "F.Cu" "F.Mask" "F.Paste")
			(net "GND")
		)
		(pad "4" smd rect
			(at 0 4.249928 90)
			(size 2.413 4.5212)
			(layers "F.Cu" "F.Mask" "F.Paste")
			(net "PVDDCR_SOC_P0")
		)
	)
	(footprint ""
		(layer "F.Cu")
		(at 91.568524 -408.517344 -90)
		(property "Reference" "C6657"
			(at 0 0 270)
			(layer "F.SilkS")
			(hide yes)
			(effects
				(font
					(size 1.27 1.27)
				)
			)
		)
		(property "Value" ""
			(at 0 0 270)
			(layer "F.Fab")
			(effects
				(font
					(size 1.27 1.27)
				)
			)
		)
		(duplicate_pad_numbers_are_jumpers no)
		(fp_line
			(start -0.299974 0.150114)
			(end -0.299974 -0.150114)
			(stroke
				(width 0.1)
				(type default)
			)
			(layer "F.Fab")
		)
		(fp_line
			(start 0.299974 0.150114)
			(end -0.299974 0.150114)
			(stroke
				(width 0.1)
				(type default)
			)
			(layer "F.Fab")
		)
		(fp_line
			(start -0.299974 -0.150114)
			(end 0.299974 -0.150114)
			(stroke
				(width 0.1)
				(type default)
			)
			(layer "F.Fab")
		)
		(fp_line
			(start 0.299974 -0.150114)
			(end 0.299974 0.150114)
			(stroke
				(width 0.1)
				(type default)
			)
			(layer "F.Fab")
		)
		(pad "1" smd rect
			(at -0.2667 0 270)
			(size 0.3048 0.381)
			(layers "F.Cu" "F.Mask" "F.Paste")
			(net "P5E_CPU1_P0_TX_BUF_C_DP<14>")
		)
		(pad "2" smd rect
			(at 0.2667 0 270)
			(size 0.3048 0.381)
			(layers "F.Cu" "F.Mask" "F.Paste")
			(net "P5E_CPU1_P0_TX_BUF_DP<14>")
		)
	)
)
